# T6G (Grand Teton) — schematic netlist excerpt (pin names and nets, part order shuffled) for the footprints in the layout excerpt that follows; sources: Cadence DE-HDL packaged netlist, KiCad conversion of 04192023_DAF0TMB3IC0_F0TG_MB_C_brd_V02_OCP.brd

PR3991  Q_RES  2K 0.1% CHIP  pkg 0402LF  page 264 : A = HSC_IMON ; B = AGND_HSC
PC71  Q_CAP  3300PF 50V 10% X7R  pkg 0402  page 200 : A = VSENSE_PVDDIO_P0_VSEN1 ; B = VSENSE_VSS_SENSE_B_P0

(kicad_pcb
	(version 20260206)
	(generator "pcbnew")
	(generator_version "10.0")
	(general
		(thickness 1.6)
		(legacy_teardrops no)
	)
	(paper "A4")
	(title_block
		(title "04192023_DAF0TMB3IC0_F0TG_MB_C_brd_V02_OCP.brd")
		(comment 1 "Grand Teton / footprints 4596-4597 of 8354")
	)
	(layers
		(0 "F.Cu" signal "TOP")
		(4 "In1.Cu" signal "GND")
		(6 "In2.Cu" signal "IN1")
		(8 "In3.Cu" signal "GND1")
		(10 "In4.Cu" signal "IN2")
		(12 "In5.Cu" signal "GND2")
		(14 "In6.Cu" signal "IN3")
		(16 "In7.Cu" signal "GND3")
		(18 "In8.Cu" signal "VCC")
		(20 "In9.Cu" signal "VCC1")
		(22 "In10.Cu" signal "GND4")
		(24 "In11.Cu" signal "IN4")
		(26 "In12.Cu" signal "GND5")
		(28 "In13.Cu" signal "IN5")
		(30 "In14.Cu" signal "GND6")
		(32 "In15.Cu" signal "IN6")
		(34 "In16.Cu" signal "GND7")
		(2 "B.Cu" signal "BOTTOM")
		(9 "F.Adhes" user "F.Adhesive")
		(11 "B.Adhes" user "B.Adhesive")
		(13 "F.Paste" user "Package Geometry/Pastemask Top")
		(15 "B.Paste" user "Package Geometry/Pastemask Bottom")
		(5 "F.SilkS" user "Ref Des/Silkscreen Top")
		(7 "B.SilkS" user "Ref Des/Silkscreen Bottom")
		(1 "F.Mask" user "Board Geometry/Soldermask Top")
		(3 "B.Mask" user "Board Geometry/Soldermask Bottom")
		(17 "Dwgs.User" user "User.Drawings")
		(19 "Cmts.User" user "User.Comments")
		(21 "Eco1.User" user "User.Eco1")
		(23 "Eco2.User" user "User.Eco2")
		(25 "Edge.Cuts" user "Board Geometry/Outline")
		(27 "Margin" user)
		(31 "F.CrtYd" user "Package Geometry/Place Bound Top")
		(29 "B.CrtYd" user "Package Geometry/Place Bound Bottom")
		(35 "F.Fab" user "Ref Des/Assembly Top")
		(33 "B.Fab" user "Ref Des/Assembly Bottom")
	)
	(footprint ""
		(layer "F.Cu")
		(at 226.0981 -401.988782 180)
		(property "Reference" "PR3991"
			(at 0 0 180)
			(layer "F.SilkS")
			(hide yes)
			(effects
				(font
					(size 1.27 1.27)
				)
			)
		)
		(property "Value" ""
			(at 0 0 180)
			(layer "F.Fab")
			(effects
				(font
					(size 1.27 1.27)
				)
			)
		)
		(duplicate_pad_numbers_are_jumpers no)
		(fp_line
			(start 0.7874 0.4064)
			(end -0.7874 0.4064)
			(stroke
				(width 0.1524)
				(type default)
			)
			(layer "F.SilkS")
		)
		(fp_line
			(start 0.7874 -0.4064)
			(end 0.7874 0.4064)
			(stroke
				(width 0.1524)
				(type default)
			)
			(layer "F.SilkS")
		)
		(fp_line
			(start -0.7874 0.4064)
			(end -0.7874 -0.4064)
			(stroke
				(width 0.1524)
				(type default)
			)
			(layer "F.SilkS")
		)
		(fp_line
			(start -0.7874 -0.4064)
			(end 0.7874 -0.4064)
			(stroke
				(width 0.1524)
				(type default)
			)
			(layer "F.SilkS")
		)
		(fp_line
			(start 0.67945 0.3048)
			(end 0.120396 0.3048)
			(stroke
				(width 0.1)
				(type default)
			)
			(layer "F.Fab")
		)
		(fp_line
			(start 0.67945 -0.3048)
			(end 0.67945 0.3048)
			(stroke
				(width 0.1)
				(type default)
			)
			(layer "F.Fab")
		)
		(fp_line
			(start 0.12065 -0.2794)
			(end 0.12065 -0.3048)
			(stroke
				(width 0.1)
				(type default)
			)
			(layer "F.Fab")
		)
		(fp_line
			(start 0.12065 -0.3048)
			(end 0.67945 -0.3048)
			(stroke
				(width 0.1)
				(type default)
			)
			(layer "F.Fab")
		)
		(fp_line
			(start 0.120396 0.3048)
			(end 0.120396 0.2794)
			(stroke
				(width 0.1)
				(type default)
			)
			(layer "F.Fab")
		)
		(fp_line
			(start 0.120396 0.2794)
			(end -0.12065 0.2794)
			(stroke
				(width 0.1)
				(type default)
			)
			(layer "F.Fab")
		)
		(fp_line
			(start -0.12065 0.3048)
			(end -0.67945 0.3048)
			(stroke
				(width 0.1)
				(type default)
			)
			(layer "F.Fab")
		)
		(fp_line
			(start -0.12065 0.2794)
			(end -0.12065 0.3048)
			(stroke
				(width 0.1)
				(type default)
			)
			(layer "F.Fab")
		)
		(fp_line
			(start -0.12065 -0.2794)
			(end 0.12065 -0.2794)
			(stroke
				(width 0.1)
				(type default)
			)
			(layer "F.Fab")
		)
		(fp_line
			(start -0.12065 -0.305054)
			(end -0.12065 -0.2794)
			(stroke
				(width 0.1)
				(type default)
			)
			(layer "F.Fab")
		)
		(fp_line
			(start -0.67945 0.3048)
			(end -0.67945 -0.305054)
			(stroke
				(width 0.1)
				(type default)
			)
			(layer "F.Fab")
		)
		(fp_line
			(start -0.67945 -0.305054)
			(end -0.12065 -0.305054)
			(stroke
				(width 0.1)
				(type default)
			)
			(layer "F.Fab")
		)
		(pad "1" smd circle
			(at -0.40005 0 180)
			(size 0 0)
			(layers "F.Cu" "F.Mask" "F.Paste")
			(net "HSC_IMON")
		)
		(pad "2" smd circle
			(at 0.40005 0 180)
			(size 0 0)
			(layers "F.Cu" "F.Mask" "F.Paste")
			(net "AGND_HSC")
		)
	)
	(footprint ""
		(layer "F.Cu")
		(at 315.341 -357.251 180)
		(property "Reference" "PC71"
			(at 0 0 180)
			(layer "F.SilkS")
			(hide yes)
			(effects
				(font
					(size 1.27 1.27)
				)
			)
		)
		(property "Value" ""
			(at 0 0 180)
			(layer "F.Fab")
			(effects
				(font
					(size 1.27 1.27)
				)
			)
		)
		(duplicate_pad_numbers_are_jumpers no)
		(fp_line
			(start 0.7874 0.4064)
			(end -0.7874 0.4064)
			(stroke
				(width 0.1524)
				(type default)
			)
			(layer "F.SilkS")
		)
		(fp_line
			(start 0.7874 -0.4064)
			(end 0.7874 0.4064)
			(stroke
				(width 0.1524)
				(type default)
			)
			(layer "F.SilkS")
		)
		(fp_line
			(start -0.7874 0.4064)
			(end -0.7874 -0.4064)
			(stroke
				(width 0.1524)
				(type default)
			)
			(layer "F.SilkS")
		)
		(fp_line
			(start -0.7874 -0.4064)
			(end 0.7874 -0.4064)
			(stroke
				(width 0.1524)
				(type default)
			)
			(layer "F.SilkS")
		)
		(fp_line
			(start 0.67945 0.3048)
			(end 0.120396 0.3048)
			(stroke
				(width 0.1)
				(type default)
			)
			(layer "F.Fab")
		)
		(fp_line
			(start 0.67945 -0.3048)
			(end 0.67945 0.3048)
			(stroke
				(width 0.1)
				(type default)
			)
			(layer "F.Fab")
		)
		(fp_line
			(start 0.12065 -0.2794)
			(end 0.12065 -0.3048)
			(stroke
				(width 0.1)
				(type default)
			)
			(layer "F.Fab")
		)
		(fp_line
			(start 0.12065 -0.3048)
			(end 0.67945 -0.3048)
			(stroke
				(width 0.1)
				(type default)
			)
			(layer "F.Fab")
		)
		(fp_line
			(start 0.120396 0.3048)
			(end 0.120396 0.2794)
			(stroke
				(width 0.1)
				(type default)
			)
			(layer "F.Fab")
		)
		(fp_line
			(start 0.120396 0.2794)
			(end -0.12065 0.2794)
			(stroke
				(width 0.1)
				(type default)
			)
			(layer "F.Fab")
		)
		(fp_line
			(start -0.12065 0.3048)
			(end -0.67945 0.3048)
			(stroke
				(width 0.1)
				(type default)
			)
			(layer "F.Fab")
		)
		(fp_line
			(start -0.12065 0.2794)
			(end -0.12065 0.3048)
			(stroke
				(width 0.1)
				(type default)
			)
			(layer "F.Fab")
		)
		(fp_line
			(start -0.12065 -0.2794)
			(end 0.12065 -0.2794)
			(stroke
				(width 0.1)
				(type default)
			)
			(layer "F.Fab")
		)
		(fp_line
			(start -0.12065 -0.305054)
			(end -0.12065 -0.2794)
			(stroke
				(width 0.1)
				(type default)
			)
			(layer "F.Fab")
		)
		(fp_line
			(start -0.67945 0.3048)
			(end -0.67945 -0.305054)
			(stroke
				(width 0.1)
				(type default)
			)
			(layer "F.Fab")
		)
		(fp_line
			(start -0.67945 -0.305054)
			(end -0.12065 -0.305054)
			(stroke
				(width 0.1)
				(type default)
			)
			(layer "F.Fab")
		)
		(pad "1" smd circle
			(at -0.40005 0 180)
			(size 0 0)
			(layers "F.Cu" "F.Mask" "F.Paste")
			(net "VSENSE_PVDDIO_P0_VSEN1")
		)
		(pad "2" smd circle
			(at 0.40005 0 180)
			(size 0 0)
			(layers "F.Cu" "F.Mask" "F.Paste")
			(net "VSENSE_VSS_SENSE_B_P0")
		)
	)
)
